# T6G (Grand Teton) — schematic netlist excerpt (pin names and nets, part order shuffled) for the footprints in the layout excerpt that follows; sources: Cadence DE-HDL packaged netlist, KiCad conversion of 04192023_DAF0TMB3IC0_F0TG_MB_C_brd_V02_OCP.brd

R6774  Q_RES  4.7K 5% CHIP  pkg 0201LF  page 184 : A = RT_SMB_MUX_ADDR1 ; B = GND
C2515  Q_CAP  10UF 6.3V 20% X6S  pkg C0402  page 71 : A = PVDD_33_S5 ; B = GND
PC416_3  Q_CAP  22UF 16V 20% X6S  pkg C0805  page 219 : A = SW_P12V_AUX_PVDDCR_CPU1_P1_FLT ; B = GND
PC227_1  Q_CAP  22UF 4V 20% X6S  pkg C0805  page 208 : A = PVDD11_S3_P0 ; B = GND

(kicad_pcb
	(version 20260206)
	(generator "pcbnew")
	(generator_version "10.0")
	(general
		(thickness 1.6)
		(legacy_teardrops no)
	)
	(paper "A4")
	(title_block
		(title "04192023_DAF0TMB3IC0_F0TG_MB_C_brd_V02_OCP.brd")
		(comment 1 "Grand Teton / footprints 7006-7009 of 8354")
	)
	(layers
		(0 "F.Cu" signal "TOP")
		(4 "In1.Cu" signal "GND")
		(6 "In2.Cu" signal "IN1")
		(8 "In3.Cu" signal "GND1")
		(10 "In4.Cu" signal "IN2")
		(12 "In5.Cu" signal "GND2")
		(14 "In6.Cu" signal "IN3")
		(16 "In7.Cu" signal "GND3")
		(18 "In8.Cu" signal "VCC")
		(20 "In9.Cu" signal "VCC1")
		(22 "In10.Cu" signal "GND4")
		(24 "In11.Cu" signal "IN4")
		(26 "In12.Cu" signal "GND5")
		(28 "In13.Cu" signal "IN5")
		(30 "In14.Cu" signal "GND6")
		(32 "In15.Cu" signal "IN6")
		(34 "In16.Cu" signal "GND7")
		(2 "B.Cu" signal "BOTTOM")
		(9 "F.Adhes" user "F.Adhesive")
		(11 "B.Adhes" user "B.Adhesive")
		(13 "F.Paste" user "Package Geometry/Pastemask Top")
		(15 "B.Paste" user "Package Geometry/Pastemask Bottom")
		(5 "F.SilkS" user "Ref Des/Silkscreen Top")
		(7 "B.SilkS" user "Ref Des/Silkscreen Bottom")
		(1 "F.Mask" user "Board Geometry/Soldermask Top")
		(3 "B.Mask" user "Board Geometry/Soldermask Bottom")
		(17 "Dwgs.User" user "User.Drawings")
		(19 "Cmts.User" user "User.Comments")
		(21 "Eco1.User" user "User.Eco1")
		(23 "Eco2.User" user "User.Eco2")
		(25 "Edge.Cuts" user "Board Geometry/Outline")
		(27 "Margin" user)
		(31 "F.CrtYd" user "Package Geometry/Place Bound Top")
		(29 "B.CrtYd" user "Package Geometry/Place Bound Bottom")
		(35 "F.Fab" user "Ref Des/Assembly Top")
		(33 "B.Fab" user "Ref Des/Assembly Bottom")
	)
	(footprint ""
		(layer "B.Cu")
		(at 214.884 -331.724)
		(property "Reference" "R6774"
			(at 0 0 0)
			(layer "B.SilkS")
			(hide yes)
			(effects
				(font
					(size 1.27 1.27)
				)
				(justify mirror)
			)
		)
		(property "Value" ""
			(at 0 0 0)
			(layer "B.Fab")
			(effects
				(font
					(size 1.27 1.27)
				)
				(justify mirror)
			)
		)
		(duplicate_pad_numbers_are_jumpers no)
		(fp_line
			(start -0.32512 -0.175006)
			(end -0.32512 0.175006)
			(stroke
				(width 0.1)
				(type default)
			)
			(layer "B.Fab")
		)
		(fp_line
			(start -0.32512 0.175006)
			(end 0.32512 0.175006)
			(stroke
				(width 0.1)
				(type default)
			)
			(layer "B.Fab")
		)
		(fp_line
			(start 0.32512 -0.175006)
			(end -0.32512 -0.175006)
			(stroke
				(width 0.1)
				(type default)
			)
			(layer "B.Fab")
		)
		(fp_line
			(start 0.32512 0.175006)
			(end 0.32512 -0.175006)
			(stroke
				(width 0.1)
				(type default)
			)
			(layer "B.Fab")
		)
		(pad "1" smd rect
			(at 0.2667 0 180)
			(size 0.3048 0.381)
			(layers "B.Cu" "B.Mask" "B.Paste")
			(net "RT_SMB_MUX_ADDR1")
		)
		(pad "2" smd rect
			(at -0.2667 0)
			(size 0.3048 0.381)
			(layers "B.Cu" "B.Mask" "B.Paste")
			(net "GND")
		)
	)
	(footprint ""
		(layer "B.Cu")
		(at 346.532454 -266.64031)
		(property "Reference" "C2515"
			(at 0 0 0)
			(layer "B.SilkS")
			(hide yes)
			(effects
				(font
					(size 1.27 1.27)
				)
				(justify mirror)
			)
		)
		(property "Value" ""
			(at 0 0 0)
			(layer "B.Fab")
			(effects
				(font
					(size 1.27 1.27)
				)
				(justify mirror)
			)
		)
		(duplicate_pad_numbers_are_jumpers no)
		(fp_line
			(start -0.7874 -0.4064)
			(end -0.7874 0.4064)
			(stroke
				(width 0.1524)
				(type default)
			)
			(layer "B.SilkS")
		)
		(fp_line
			(start -0.7874 0.4064)
			(end 0.7874 0.4064)
			(stroke
				(width 0.1524)
				(type default)
			)
			(layer "B.SilkS")
		)
		(fp_line
			(start 0.7874 -0.4064)
			(end -0.7874 -0.4064)
			(stroke
				(width 0.1524)
				(type default)
			)
			(layer "B.SilkS")
		)
		(fp_line
			(start 0.7874 0.4064)
			(end 0.7874 -0.4064)
			(stroke
				(width 0.1524)
				(type default)
			)
			(layer "B.SilkS")
		)
		(fp_line
			(start -0.67945 -0.3048)
			(end -0.67945 0.3048)
			(stroke
				(width 0.1)
				(type default)
			)
			(layer "B.Fab")
		)
		(fp_line
			(start -0.67945 0.3048)
			(end -0.120396 0.3048)
			(stroke
				(width 0.1)
				(type default)
			)
			(layer "B.Fab")
		)
		(fp_line
			(start -0.12065 -0.3048)
			(end -0.67945 -0.3048)
			(stroke
				(width 0.1)
				(type default)
			)
			(layer "B.Fab")
		)
		(fp_line
			(start -0.12065 -0.2794)
			(end -0.12065 -0.3048)
			(stroke
				(width 0.1)
				(type default)
			)
			(layer "B.Fab")
		)
		(fp_line
			(start -0.120396 0.2794)
			(end 0.12065 0.2794)
			(stroke
				(width 0.1)
				(type default)
			)
			(layer "B.Fab")
		)
		(fp_line
			(start -0.120396 0.3048)
			(end -0.120396 0.2794)
			(stroke
				(width 0.1)
				(type default)
			)
			(layer "B.Fab")
		)
		(fp_line
			(start 0.12065 -0.305054)
			(end 0.12065 -0.2794)
			(stroke
				(width 0.1)
				(type default)
			)
			(layer "B.Fab")
		)
		(fp_line
			(start 0.12065 -0.2794)
			(end -0.12065 -0.2794)
			(stroke
				(width 0.1)
				(type default)
			)
			(layer "B.Fab")
		)
		(fp_line
			(start 0.12065 0.2794)
			(end 0.12065 0.3048)
			(stroke
				(width 0.1)
				(type default)
			)
			(layer "B.Fab")
		)
		(fp_line
			(start 0.12065 0.3048)
			(end 0.67945 0.3048)
			(stroke
				(width 0.1)
				(type default)
			)
			(layer "B.Fab")
		)
		(fp_line
			(start 0.67945 -0.305054)
			(end 0.12065 -0.305054)
			(stroke
				(width 0.1)
				(type default)
			)
			(layer "B.Fab")
		)
		(fp_line
			(start 0.67945 0.3048)
			(end 0.67945 -0.305054)
			(stroke
				(width 0.1)
				(type default)
			)
			(layer "B.Fab")
		)
		(pad "1" smd circle
			(at 0.40005 0 180)
			(size 0 0)
			(layers "B.Cu" "B.Mask" "B.Paste")
			(net "PVDD_33_S5")
		)
		(pad "2" smd circle
			(at -0.40005 0 180)
			(size 0 0)
			(layers "B.Cu" "B.Mask" "B.Paste")
			(net "GND")
		)
	)
	(footprint ""
		(layer "B.Cu")
		(at 71.530718 -335.06791 90)
		(property "Reference" "PC416_3"
			(at 0 0 90)
			(layer "B.SilkS")
			(hide yes)
			(effects
				(font
					(size 1.27 1.27)
				)
				(justify mirror)
			)
		)
		(property "Value" ""
			(at 0 0 90)
			(layer "B.Fab")
			(effects
				(font
					(size 1.27 1.27)
				)
				(justify mirror)
			)
		)
		(duplicate_pad_numbers_are_jumpers no)
		(fp_line
			(start 1.524 -0.762)
			(end -1.524 -0.762)
			(stroke
				(width 0.1524)
				(type default)
			)
			(layer "B.SilkS")
		)
		(fp_line
			(start -1.524 -0.762)
			(end -1.524 0.762)
			(stroke
				(width 0.1524)
				(type default)
			)
			(layer "B.SilkS")
		)
		(fp_line
			(start 1.524 0.762)
			(end 1.524 -0.762)
			(stroke
				(width 0.1524)
				(type default)
			)
			(layer "B.SilkS")
		)
		(fp_line
			(start -1.524 0.762)
			(end 1.524 0.762)
			(stroke
				(width 0.1524)
				(type default)
			)
			(layer "B.SilkS")
		)
		(fp_line
			(start 1.1049 -0.724916)
			(end 1.1049 0.724916)
			(stroke
				(width 0.1)
				(type default)
			)
			(layer "B.Fab")
		)
		(fp_line
			(start -1.1049 -0.724916)
			(end 1.1049 -0.724916)
			(stroke
				(width 0.1)
				(type default)
			)
			(layer "B.Fab")
		)
		(fp_line
			(start 1.1049 0.724916)
			(end -1.1049 0.724916)
			(stroke
				(width 0.1)
				(type default)
			)
			(layer "B.Fab")
		)
		(fp_line
			(start -1.1049 0.724916)
			(end -1.1049 -0.724916)
			(stroke
				(width 0.1)
				(type default)
			)
			(layer "B.Fab")
		)
		(pad "1" smd rect
			(at 0.889 0 90)
			(size 1.016 1.27)
			(layers "B.Cu" "B.Mask" "B.Paste")
			(net "SW_P12V_AUX_PVDDCR_CPU1_P1_FLT")
		)
		(pad "2" smd rect
			(at -0.889 0 90)
			(size 1.016 1.27)
			(layers "B.Cu" "B.Mask" "B.Paste")
			(net "GND")
		)
	)
	(footprint ""
		(layer "B.Cu")
		(at 435.406292 -341.921846 -90)
		(property "Reference" "PC227_1"
			(at 0 0 90)
			(layer "B.SilkS")
			(hide yes)
			(effects
				(font
					(size 1.27 1.27)
				)
				(justify mirror)
			)
		)
		(property "Value" ""
			(at 0 0 90)
			(layer "B.Fab")
			(effects
				(font
					(size 1.27 1.27)
				)
				(justify mirror)
			)
		)
		(duplicate_pad_numbers_are_jumpers no)
		(fp_line
			(start -1.524 0.762)
			(end 1.524 0.762)
			(stroke
				(width 0.1524)
				(type default)
			)
			(layer "B.SilkS")
		)
		(fp_line
			(start 1.524 0.762)
			(end 1.524 -0.762)
			(stroke
				(width 0.1524)
				(type default)
			)
			(layer "B.SilkS")
		)
		(fp_line
			(start -1.524 -0.762)
			(end -1.524 0.762)
			(stroke
				(width 0.1524)
				(type default)
			)
			(layer "B.SilkS")
		)
		(fp_line
			(start 1.524 -0.762)
			(end -1.524 -0.762)
			(stroke
				(width 0.1524)
				(type default)
			)
			(layer "B.SilkS")
		)
		(fp_line
			(start -1.1049 0.724916)
			(end -1.1049 -0.724916)
			(stroke
				(width 0.1)
				(type default)
			)
			(layer "B.Fab")
		)
		(fp_line
			(start 1.1049 0.724916)
			(end -1.1049 0.724916)
			(stroke
				(width 0.1)
				(type default)
			)
			(layer "B.Fab")
		)
		(fp_line
			(start -1.1049 -0.724916)
			(end 1.1049 -0.724916)
			(stroke
				(width 0.1)
				(type default)
			)
			(layer "B.Fab")
		)
		(fp_line
			(start 1.1049 -0.724916)
			(end 1.1049 0.724916)
			(stroke
				(width 0.1)
				(type default)
			)
			(layer "B.Fab")
		)
		(pad "1" smd rect
			(at 0.889 0 270)
			(size 1.016 1.27)
			(layers "B.Cu" "B.Mask" "B.Paste")
			(net "PVDD11_S3_P0")
		)
		(pad "2" smd rect
			(at -0.889 0 270)
			(size 1.016 1.27)
			(layers "B.Cu" "B.Mask" "B.Paste")
			(net "GND")
		)
	)
)
